(kicad_pcb
	(version 20241229)
	(generator "pcbnew")
	(generator_version "9.0")
	(general
		(thickness 1.6)
		(legacy_teardrops no)
	)
	(paper "A4")
	(title_block
		(title "GMSL Deserializer")
		(date "2025-10-09")
		(rev "1.0.4")
		(company "Antmicro Ltd")
		(comment 1 "www.antmicro.com")
		(comment 9 "footprints 165-170 of 235")
	)
	(layers
		(0 "F.Cu" signal)
		(4 "In1.Cu" power)
		(6 "In2.Cu" power)
		(2 "B.Cu" signal)
		(9 "F.Adhes" user "F.Adhesive")
		(11 "B.Adhes" user "B.Adhesive")
		(13 "F.Paste" user)
		(15 "B.Paste" user)
		(5 "F.SilkS" user "F.Silkscreen")
		(7 "B.SilkS" user "B.Silkscreen")
		(1 "F.Mask" user)
		(3 "B.Mask" user)
		(17 "Dwgs.User" user "User.Drawings")
		(19 "Cmts.User" user "User.Comments")
		(21 "Eco1.User" user "User.Eco1")
		(23 "Eco2.User" user "User.Eco2")
		(25 "Edge.Cuts" user)
		(27 "Margin" user)
		(31 "F.CrtYd" user "F.Courtyard")
		(29 "B.CrtYd" user "B.Courtyard")
		(35 "F.Fab" user)
		(33 "B.Fab" user)
	)
	(footprint "antmicro-footprints:DFN-10_2.5x1mm"
		(layer "F.Cu")
		(at 142.598 77.076 -45)
		(property "Reference" "D4"
			(at 1.22881 -1.358635 225)
			(layer "F.SilkS")
			(effects
				(font
					(size 0.7 0.7)
					(thickness 0.15)
				)
				(justify left bottom)
			)
		)
		(property "Value" "PESD4USB5U-TTS"
			(at 2.032 1.524 135)
			(layer "F.Fab")
			(effects
				(font
					(size 0.7 0.7)
					(thickness 0.15)
				)
				(justify right bottom)
			)
		)
		(property "Datasheet" "https://assets.nexperia.com/documents/data-sheet/PESD4USB5U-TTS.pdf"
			(at 0 0 315)
			(layer "F.Fab")
			(hide yes)
			(effects
				(font
					(size 1.27 1.27)
					(thickness 0.15)
				)
			)
		)
		(property "Description" "TVS diode array, 15kV, DFN-10, 5 V, 0.5 pF"
			(at 0 0 315)
			(layer "F.Fab")
			(hide yes)
			(effects
				(font
					(size 1.27 1.27)
					(thickness 0.15)
				)
			)
		)
		(property "Author" "Antmicro"
			(at -12.790036 123.554121 0)
			(layer "F.Fab")
			(hide yes)
			(effects
				(font
					(size 1 1)
					(thickness 0.15)
				)
			)
		)
		(property "License" "Apache-2.0"
			(at -12.790036 123.554121 0)
			(layer "F.Fab")
			(hide yes)
			(effects
				(font
					(size 1 1)
					(thickness 0.15)
				)
			)
		)
		(property "MPN" "PESD4USB5U-TTS"
			(at -12.790036 123.554121 0)
			(layer "F.Fab")
			(hide yes)
			(effects
				(font
					(size 1 1)
					(thickness 0.15)
				)
			)
		)
		(property "Manufacturer" "Nexperia"
			(at -12.790036 123.554121 0)
			(layer "F.Fab")
			(hide yes)
			(effects
				(font
					(size 1 1)
					(thickness 0.15)
				)
			)
		)
		(sheetname "/Deserializer/")
		(sheetfile "deserializer.kicad_sch")
		(attr smd)
		(fp_line
			(start -0.4 1.4)
			(end 0.4 1.4)
			(stroke
				(width 0.15)
				(type solid)
			)
			(layer "F.SilkS")
		)
		(fp_line
			(start 0.4 -1.4)
			(end -0.4 -1.4)
			(stroke
				(width 0.15)
				(type solid)
			)
			(layer "F.SilkS")
		)
		(fp_circle
			(center -0.762 -1.27)
			(end -0.712 -1.270001)
			(stroke
				(width 0.15)
				(type solid)
			)
			(fill yes)
			(layer "F.SilkS")
		)
		(fp_poly
			(pts
				(xy -0.85 -1.6) (xy 0.85 -1.6) (xy 0.85 1.6) (xy -0.85 1.6)
			)
			(stroke
				(width 0.05)
				(type solid)
			)
			(fill no)
			(layer "F.CrtYd")
		)
		(fp_line
			(start -0.5 1.25)
			(end 0.5 1.25)
			(stroke
				(width 0.15)
				(type solid)
			)
			(layer "F.Fab")
		)
		(fp_line
			(start 0.5 1.25)
			(end 0.5 -1.25)
			(stroke
				(width 0.15)
				(type solid)
			)
			(layer "F.Fab")
		)
		(fp_line
			(start -0.499999 -0.9)
			(end -0.5 1.25)
			(stroke
				(width 0.15)
				(type solid)
			)
			(layer "F.Fab")
		)
		(fp_line
			(start -0.15 -1.249999)
			(end -0.499999 -0.9)
			(stroke
				(width 0.15)
				(type solid)
			)
			(layer "F.Fab")
		)
		(fp_line
			(start 0.5 -1.25)
			(end -0.15 -1.249999)
			(stroke
				(width 0.15)
				(type solid)
			)
			(layer "F.Fab")
		)
		(pad "1" smd roundrect
			(at -0.425 -1 225)
			(size 0.2 0.6)
			(layers "F.Cu" "F.Mask" "F.Paste")
			(roundrect_rratio 0.25)
			(net 14 "/Deserializer/SIOB_P")
			(pinfunction "1")
			(pintype "passive")
			(solder_mask_margin 0.05)
		)
		(pad "2" smd roundrect
			(at -0.425 -0.5 225)
			(size 0.2 0.6)
			(layers "F.Cu" "F.Mask" "F.Paste")
			(roundrect_rratio 0.25)
			(net 20 "/Deserializer/SIOB_N")
			(pinfunction "2")
			(pintype "passive")
			(solder_mask_margin 0.05)
		)
		(pad "3" smd roundrect
			(at -0.424999 0 225)
			(size 0.4 0.6)
			(layers "F.Cu" "F.Mask" "F.Paste")
			(roundrect_rratio 0.25)
			(net 1 "GND")
			(pinfunction "3")
			(pintype "passive")
			(solder_mask_margin 0.05)
		)
		(pad "4" smd roundrect
			(at -0.425 0.5 225)
			(size 0.2 0.6)
			(layers "F.Cu" "F.Mask" "F.Paste")
			(roundrect_rratio 0.25)
			(net 18 "/Deserializer/SIOA_N")
			(pinfunction "4")
			(pintype "passive")
			(solder_mask_margin 0.05)
		)
		(pad "5" smd roundrect
			(at -0.425 1 225)
			(size 0.2 0.6)
			(layers "F.Cu" "F.Mask" "F.Paste")
			(roundrect_rratio 0.25)
			(net 13 "/Deserializer/SIOA_P")
			(pinfunction "5")
			(pintype "passive")
			(solder_mask_margin 0.05)
		)
		(pad "6" smd roundrect
			(at 0.425 1 225)
			(size 0.2 0.6)
			(layers "F.Cu" "F.Mask" "F.Paste")
			(roundrect_rratio 0.25)
			(net 13 "/Deserializer/SIOA_P")
			(pinfunction "6")
			(pintype "passive")
			(solder_mask_margin 0.05)
		)
		(pad "7" smd roundrect
			(at 0.425 0.5 225)
			(size 0.2 0.6)
			(layers "F.Cu" "F.Mask" "F.Paste")
			(roundrect_rratio 0.25)
			(net 18 "/Deserializer/SIOA_N")
			(pinfunction "7")
			(pintype "passive")
			(solder_mask_margin 0.05)
		)
		(pad "8" smd roundrect
			(at 0.424999 0 225)
			(size 0.4 0.6)
			(layers "F.Cu" "F.Mask" "F.Paste")
			(roundrect_rratio 0.25)
			(net 1 "GND")
			(pinfunction "8")
			(pintype "passive")
			(solder_mask_margin 0.05)
		)
		(pad "9" smd roundrect
			(at 0.425 -0.5 225)
			(size 0.2 0.6)
			(layers "F.Cu" "F.Mask" "F.Paste")
			(roundrect_rratio 0.25)
			(net 20 "/Deserializer/SIOB_N")
			(pinfunction "9")
			(pintype "passive")
			(solder_mask_margin 0.05)
		)
		(pad "10" smd roundrect
			(at 0.425 -1 225)
			(size 0.2 0.6)
			(layers "F.Cu" "F.Mask" "F.Paste")
			(roundrect_rratio 0.25)
			(net 14 "/Deserializer/SIOB_P")
			(pinfunction "10")
			(pintype "passive")
			(solder_mask_margin 0.05)
		)
	)
	(footprint "antmicro-footprints:R_0402_1005Metric"
		(layer "F.Cu")
		(at 175.195 66.418 180)
		(descr "Resistor SMD 0402")
		(tags "resistor SMD 0402")
		(property "Reference" "R60"
			(at -1.320513 -1.324079 0)
			(layer "F.SilkS")
			(effects
				(font
					(size 0.7 0.7)
					(thickness 0.15)
				)
				(justify right bottom)
			)
		)
		(property "Value" "R_10k_0402"
			(at -1.011843 1.772047 0)
			(layer "F.Fab")
			(effects
				(font
					(size 0.7 0.7)
					(thickness 0.15)
				)
				(justify right bottom)
			)
		)
		(property "Datasheet" "https://www.bourns.com/docs/product-datasheets/cr.pdf"
			(at 0 0 180)
			(layer "F.Fab")
			(hide yes)
			(effects
				(font
					(size 1.27 1.27)
					(thickness 0.15)
				)
			)
		)
		(property "Description" "SMD Chip Resistor, 10 kohm, ± 1%, 62.5 mW, 0402 [1005 Metric], Thick Film, General Purpose"
			(at 0 0 180)
			(layer "F.Fab")
			(hide yes)
			(effects
				(font
					(size 1.27 1.27)
					(thickness 0.15)
				)
			)
		)
		(property "Author" "Antmicro"
			(at 350.39 132.836 0)
			(layer "F.Fab")
			(hide yes)
			(effects
				(font
					(size 1 1)
					(thickness 0.15)
				)
			)
		)
		(property "License" "Apache-2.0"
			(at 350.39 132.836 0)
			(layer "F.Fab")
			(hide yes)
			(effects
				(font
					(size 1 1)
					(thickness 0.15)
				)
			)
		)
		(property "MPN" "CR0402-FX-1002GLF"
			(at 350.39 132.836 0)
			(layer "F.Fab")
			(hide yes)
			(effects
				(font
					(size 1 1)
					(thickness 0.15)
				)
			)
		)
		(property "Manufacturer" "Bourns"
			(at 350.39 132.836 0)
			(layer "F.Fab")
			(hide yes)
			(effects
				(font
					(size 1 1)
					(thickness 0.15)
				)
			)
		)
		(property "Tolerance" "1%"
			(at 350.39 132.836 0)
			(layer "F.Fab")
			(hide yes)
			(effects
				(font
					(size 1 1)
					(thickness 0.15)
				)
			)
		)
		(property "Val" "10k"
			(at 350.39 132.836 0)
			(layer "F.Fab")
			(hide yes)
			(effects
				(font
					(size 1 1)
					(thickness 0.15)
				)
			)
		)
		(sheetname "/Connectors/")
		(sheetfile "connectors.kicad_sch")
		(attr smd)
		(fp_rect
			(start -0.925 -0.47)
			(end 0.925 0.47)
			(stroke
				(width 0.05)
				(type default)
			)
			(fill no)
			(layer "F.CrtYd")
		)
		(fp_rect
			(start -0.5 -0.25)
			(end 0.5 0.25)
			(stroke
				(width 0.15)
				(type solid)
			)
			(fill no)
			(layer "F.Fab")
		)
		(pad "1" smd roundrect
			(at -0.48 0 180)
			(size 0.59 0.64)
			(layers "F.Cu" "F.Mask" "F.Paste")
			(roundrect_rratio 0.25)
			(net 135 "Net-(U8-OE)")
			(pintype "passive")
		)
		(pad "2" smd roundrect
			(at 0.48 0 180)
			(size 0.59 0.64)
			(layers "F.Cu" "F.Mask" "F.Paste")
			(roundrect_rratio 0.25)
			(net 3 "+1V8")
			(pintype "passive")
		)
	)
	(footprint "antmicro-footprints:R_0402_1005Metric"
		(layer "F.Cu")
		(at 178.482 62.076 -90)
		(descr "Resistor SMD 0402")
		(tags "resistor SMD 0402")
		(property "Reference" "R61"
			(at 8.028 -0.588 90)
			(layer "F.SilkS")
			(effects
				(font
					(size 0.7 0.7)
					(thickness 0.15)
				)
				(justify right bottom)
			)
		)
		(property "Value" "R_2k2_0402"
			(at -1.011843 1.772047 90)
			(layer "F.Fab")
			(effects
				(font
					(size 0.7 0.7)
					(thickness 0.15)
				)
				(justify right bottom)
			)
		)
		(property "Datasheet" "https://www.bourns.com/docs/product-datasheets/cr.pdf"
			(at 0 0 270)
			(layer "F.Fab")
			(hide yes)
			(effects
				(font
					(size 1.27 1.27)
					(thickness 0.15)
				)
			)
		)
		(property "Description" "SMD Chip Resistor, 2.2 kohm, ± 1%, 62.5 mW, 0402 [1005 Metric], Thick Film, General Purpose"
			(at 0 0 270)
			(layer "F.Fab")
			(hide yes)
			(effects
				(font
					(size 1.27 1.27)
					(thickness 0.15)
				)
			)
		)
		(property "Author" "Antmicro"
			(at 116.406 240.558 0)
			(layer "F.Fab")
			(hide yes)
			(effects
				(font
					(size 1 1)
					(thickness 0.15)
				)
			)
		)
		(property "License" "Apache-2.0"
			(at 116.406 240.558 0)
			(layer "F.Fab")
			(hide yes)
			(effects
				(font
					(size 1 1)
					(thickness 0.15)
				)
			)
		)
		(property "MPN" "CR0402-FX-2201GLF"
			(at 116.406 240.558 0)
			(layer "F.Fab")
			(hide yes)
			(effects
				(font
					(size 1 1)
					(thickness 0.15)
				)
			)
		)
		(property "Manufacturer" "Bourns"
			(at 116.406 240.558 0)
			(layer "F.Fab")
			(hide yes)
			(effects
				(font
					(size 1 1)
					(thickness 0.15)
				)
			)
		)
		(property "Tolerance" "1%"
			(at 116.406 240.558 0)
			(layer "F.Fab")
			(hide yes)
			(effects
				(font
					(size 1 1)
					(thickness 0.15)
				)
			)
		)
		(property "Val" "2k2"
			(at 116.406 240.558 0)
			(layer "F.Fab")
			(hide yes)
			(effects
				(font
					(size 1 1)
					(thickness 0.15)
				)
			)
		)
		(sheetname "/Connectors/")
		(sheetfile "connectors.kicad_sch")
		(attr smd exclude_from_pos_files exclude_from_bom dnp)
		(fp_rect
			(start -0.925 -0.47)
			(end 0.925 0.47)
			(stroke
				(width 0.05)
				(type default)
			)
			(fill no)
			(layer "F.CrtYd")
		)
		(fp_rect
			(start -0.5 -0.25)
			(end 0.5 0.25)
			(stroke
				(width 0.15)
				(type solid)
			)
			(fill no)
			(layer "F.Fab")
		)
		(pad "1" smd roundrect
			(at -0.48 0 270)
			(size 0.59 0.64)
			(layers "F.Cu" "F.Mask" "F.Paste")
			(roundrect_rratio 0.25)
			(net 45 "/Connectors/SCL_CAM")
			(pintype "passive")
		)
		(pad "2" smd roundrect
			(at 0.48 0 270)
			(size 0.59 0.64)
			(layers "F.Cu" "F.Mask" "F.Paste")
			(roundrect_rratio 0.25)
			(net 50 "/Connectors/FFC_3V3")
			(pintype "passive")
		)
	)
	(footprint "antmicro-footprints:TP_SMD_0.75mm"
		(layer "F.Cu")
		(at 146.304 97.89)
		(property "Reference" "TP14"
			(at 0 -0.6 0)
			(layer "F.SilkS")
			(hide yes)
			(effects
				(font
					(size 0.7 0.7)
					(thickness 0.15)
				)
				(justify left bottom)
			)
		)
		(property "Value" "TP_0.75mm_SMD"
			(at 0 1.2 0)
			(layer "F.Fab")
			(effects
				(font
					(size 0.7 0.7)
					(thickness 0.15)
				)
				(justify left bottom)
			)
		)
		(property "Description" "SMT test point"
			(at 0 0 0)
			(layer "F.Fab")
			(hide yes)
			(effects
				(font
					(size 1.27 1.27)
					(thickness 0.15)
				)
			)
		)
		(property "Author" "Antmicro"
			(at 0 0 0)
			(layer "F.Fab")
			(hide yes)
			(effects
				(font
					(size 1 1)
					(thickness 0.15)
				)
			)
		)
		(property "License" "Apache-2.0"
			(at 0 0 0)
			(layer "F.Fab")
			(hide yes)
			(effects
				(font
					(size 1 1)
					(thickness 0.15)
				)
			)
		)
		(property "MPN" ""
			(at 0 0 0)
			(layer "F.Fab")
			(hide yes)
			(effects
				(font
					(size 1 1)
					(thickness 0.15)
				)
			)
		)
		(property "Manufacturer" ""
			(at 0 0 0)
			(layer "F.Fab")
			(hide yes)
			(effects
				(font
					(size 1 1)
					(thickness 0.15)
				)
			)
		)
		(sheetname "/Power/")
		(sheetfile "power.kicad_sch")
		(fp_circle
			(center 0 0)
			(end 0.475 0)
			(stroke
				(width 0.05)
				(type default)
			)
			(fill no)
			(layer "F.CrtYd")
		)
		(pad "1" smd circle
			(at 0 0)
			(size 0.75 0.75)
			(layers "F.Cu" "F.Mask")
			(net 11 "/Power/OUT_1V2")
			(pinfunction "1")
			(pintype "passive")
		)
	)
	(footprint "antmicro-footprints:R_0402_1005Metric"
		(layer "F.Cu")
		(at 121.087 81.638 -90)
		(descr "Resistor SMD 0402")
		(tags "resistor SMD 0402")
		(property "Reference" "R38"
			(at -1.12 0.564 90)
			(layer "F.SilkS")
			(effects
				(font
					(size 0.7 0.7)
					(thickness 0.15)
				)
				(justify right bottom)
			)
		)
		(property "Value" "R_10k_0402"
			(at -1.011843 1.772047 90)
			(layer "F.Fab")
			(effects
				(font
					(size 0.7 0.7)
					(thickness 0.15)
				)
				(justify right bottom)
			)
		)
		(property "Datasheet" "https://www.bourns.com/docs/product-datasheets/cr.pdf"
			(at 0 0 270)
			(layer "F.Fab")
			(hide yes)
			(effects
				(font
					(size 1.27 1.27)
					(thickness 0.15)
				)
			)
		)
		(property "Description" "SMD Chip Resistor, 10 kohm, ± 1%, 62.5 mW, 0402 [1005 Metric], Thick Film, General Purpose"
			(at 0 0 270)
			(layer "F.Fab")
			(hide yes)
			(effects
				(font
					(size 1.27 1.27)
					(thickness 0.15)
				)
			)
		)
		(property "Author" "Antmicro"
			(at 39.449 202.725 0)
			(layer "F.Fab")
			(hide yes)
			(effects
				(font
					(size 1 1)
					(thickness 0.15)
				)
			)
		)
		(property "License" "Apache-2.0"
			(at 39.449 202.725 0)
			(layer "F.Fab")
			(hide yes)
			(effects
				(font
					(size 1 1)
					(thickness 0.15)
				)
			)
		)
		(property "MPN" "CR0402-FX-1002GLF"
			(at 39.449 202.725 0)
			(layer "F.Fab")
			(hide yes)
			(effects
				(font
					(size 1 1)
					(thickness 0.15)
				)
			)
		)
		(property "Manufacturer" "Bourns"
			(at 39.449 202.725 0)
			(layer "F.Fab")
			(hide yes)
			(effects
				(font
					(size 1 1)
					(thickness 0.15)
				)
			)
		)
		(property "Tolerance" "1%"
			(at 39.449 202.725 0)
			(layer "F.Fab")
			(hide yes)
			(effects
				(font
					(size 1 1)
					(thickness 0.15)
				)
			)
		)
		(property "Val" "10k"
			(at 39.449 202.725 0)
			(layer "F.Fab")
			(hide yes)
			(effects
				(font
					(size 1 1)
					(thickness 0.15)
				)
			)
		)
		(sheetname "/Power/")
		(sheetfile "power.kicad_sch")
		(attr smd)
		(fp_rect
			(start -0.925 -0.47)
			(end 0.925 0.47)
			(stroke
				(width 0.05)
				(type default)
			)
			(fill no)
			(layer "F.CrtYd")
		)
		(fp_rect
			(start -0.5 -0.25)
			(end 0.5 0.25)
			(stroke
				(width 0.15)
				(type solid)
			)
			(fill no)
			(layer "F.Fab")
		)
		(pad "1" smd roundrect
			(at -0.48 0 270)
			(size 0.59 0.64)
			(layers "F.Cu" "F.Mask" "F.Paste")
			(roundrect_rratio 0.25)
			(net 1 "GND")
			(pintype "passive")
		)
		(pad "2" smd roundrect
			(at 0.48 0 270)
			(size 0.59 0.64)
			(layers "F.Cu" "F.Mask" "F.Paste")
			(roundrect_rratio 0.25)
			(net 71 "/Power/FB_1V2")
			(pintype "passive")
		)
	)
	(footprint "antmicro-footprints:R_0402_1005Metric"
		(layer "F.Cu")
		(at 139.192 61.976 90)
		(descr "Resistor SMD 0402")
		(tags "resistor SMD 0402")
		(property "Reference" "R20"
			(at -1.1405 1.27 90)
			(layer "F.SilkS")
			(effects
				(font
					(size 0.7 0.7)
					(thickness 0.15)
				)
				(justify left bottom)
			)
		)
		(property "Value" "R_5k1_0402"
			(at -1.011843 1.772047 90)
			(layer "F.Fab")
			(effects
				(font
					(size 0.7 0.7)
					(thickness 0.15)
				)
				(justify left bottom)
			)
		)
		(property "Datasheet" "https://www.bourns.com/docs/product-datasheets/cr.pdf"
			(at 0 0 90)
			(layer "F.Fab")
			(hide yes)
			(effects
				(font
					(size 1.27 1.27)
					(thickness 0.15)
				)
			)
		)
		(property "Description" "SMD Chip Resistor, 5.1 kohm, ± 1%, 63 mW, 0402 [1005 Metric], Thick Film, General Purpose"
			(at 0 0 90)
			(layer "F.Fab")
			(hide yes)
			(effects
				(font
					(size 1.27 1.27)
					(thickness 0.15)
				)
			)
		)
		(property "Author" "Antmicro"
			(at 201.168 -77.216 0)
			(layer "F.Fab")
			(hide yes)
			(effects
				(font
					(size 1 1)
					(thickness 0.15)
				)
			)
		)
		(property "License" "Apache-2.0"
			(at 201.168 -77.216 0)
			(layer "F.Fab")
			(hide yes)
			(effects
				(font
					(size 1 1)
					(thickness 0.15)
				)
			)
		)
		(property "MPN" "CR0402-FX-5101GLF"
			(at 201.168 -77.216 0)
			(layer "F.Fab")
			(hide yes)
			(effects
				(font
					(size 1 1)
					(thickness 0.15)
				)
			)
		)
		(property "Manufacturer" "Bourns"
			(at 201.168 -77.216 0)
			(layer "F.Fab")
			(hide yes)
			(effects
				(font
					(size 1 1)
					(thickness 0.15)
				)
			)
		)
		(property "Tolerance" "1%"
			(at 201.168 -77.216 0)
			(layer "F.Fab")
			(hide yes)
			(effects
				(font
					(size 1 1)
					(thickness 0.15)
				)
			)
		)
		(property "Val" "5k1"
			(at 201.168 -77.216 0)
			(layer "F.Fab")
			(hide yes)
			(effects
				(font
					(size 1 1)
					(thickness 0.15)
				)
			)
		)
		(sheetname "/Power/")
		(sheetfile "power.kicad_sch")
		(attr smd)
		(fp_rect
			(start -0.925 -0.47)
			(end 0.925 0.47)
			(stroke
				(width 0.05)
				(type default)
			)
			(fill no)
			(layer "F.CrtYd")
		)
		(fp_rect
			(start -0.5 -0.25)
			(end 0.5 0.25)
			(stroke
				(width 0.15)
				(type solid)
			)
			(fill no)
			(layer "F.Fab")
		)
		(pad "1" smd roundrect
			(at -0.48 0 90)
			(size 0.59 0.64)
			(layers "F.Cu" "F.Mask" "F.Paste")
			(roundrect_rratio 0.25)
			(net 4 "+12V")
			(pintype "passive")
		)
		(pad "2" smd roundrect
			(at 0.48 0 90)
			(size 0.59 0.64)
			(layers "F.Cu" "F.Mask" "F.Paste")
			(roundrect_rratio 0.25)
			(net 52 "Net-(L2-Pad2)")
			(pintype "passive")
		)
	)
)
